(kicad_pcb
	(version 20260206)
	(generator "pcbnew")
	(generator_version "10.0")
	(general
		(thickness 1.6)
		(legacy_teardrops no)
	)
	(paper "A4")
	(title_block
		(title "panther-plus-userver — 13130-1b_20150205.brd")
		(comment 1 "Honey Badger (Wiwynn) / footprint 1214 of 1509 (DIMM3), pads 170-176 of 210")
	)
	(layers
		(0 "F.Cu" signal "TOP")
		(4 "In1.Cu" signal "L2")
		(6 "In2.Cu" signal "L3")
		(8 "In3.Cu" signal "L4")
		(10 "In4.Cu" signal "L5")
		(12 "In5.Cu" signal "L6")
		(14 "In6.Cu" signal "L7")
		(16 "In7.Cu" signal "L8")
		(18 "In8.Cu" signal "L9")
		(20 "In9.Cu" signal "L10")
		(22 "In10.Cu" signal "L11")
		(2 "B.Cu" signal "BOTTOM")
		(9 "F.Adhes" user "F.Adhesive")
		(11 "B.Adhes" user "B.Adhesive")
		(13 "F.Paste" user "Package Geometry/Pastemask Top")
		(15 "B.Paste" user "Package Geometry/Pastemask Bottom")
		(5 "F.SilkS" user "Ref Des/Silkscreen Top")
		(7 "B.SilkS" user "Ref Des/Silkscreen Bottom")
		(1 "F.Mask" user "Board Geometry/Soldermask Top")
		(3 "B.Mask" user "Board Geometry/Soldermask Bottom")
		(17 "Dwgs.User" user "User.Drawings")
		(19 "Cmts.User" user "User.Comments")
		(21 "Eco1.User" user "User.Eco1")
		(23 "Eco2.User" user "User.Eco2")
		(25 "Edge.Cuts" user "Board Geometry/Outline")
		(27 "Margin" user)
		(31 "F.CrtYd" user "Package Geometry/Place Bound Top")
		(29 "B.CrtYd" user "Package Geometry/Place Bound Bottom")
		(35 "F.Fab" user "Ref Des/Assembly Top")
		(33 "B.Fab" user "Ref Des/Assembly Bottom")
	)
	(footprint ""
		(layer "B.Cu")
		(at 159.999934 -5.790692)
		(property "Reference" "DIMM3"
			(at 0 0 0)
			(layer "B.SilkS")
			(hide yes)
			(effects
				(font
					(size 1.27 1.27)
				)
				(justify mirror)
			)
		)
		(property "Value" "DDR3-204P-142-COLAY-1-GP-U"
			(at 41.312338 -16.676878 0)
			(unlocked yes)
			(layer "B.Fab")
			(hide yes)
			(effects
				(font
					(size 1.016 1.016)
					(thickness 0.1524)
				)
				(justify mirror)
			)
		)
		(property "Device Type" "AS0A626-J8R6-7H-COLAY-1"
			(at 41.312338 -18.200878 0)
			(unlocked yes)
			(layer "B.Fab")
			(hide yes)
			(effects
				(font
					(size 1.016 1.016)
					(thickness 0.1524)
				)
				(justify mirror)
			)
		)
		(duplicate_pad_numbers_are_jumpers no)
		(pad "168" smd custom
			(at 20.850098 4.100068 180)
			(size 0.1143 0.1143)
			(layers "B.Cu" "B.Mask" "B.Paste")
			(net "M_B_DQ53")
			(options
				(clearance outline)
				(anchor circle)
			)
			(primitives
				(gr_poly
					(pts
						(xy 0 -0.9017) (xy -0.03175 -0.89916) (xy -0.0635 -0.889) (xy -0.09144 -0.87376) (xy -0.11684 -0.85344)
						(xy -0.13716 -0.82804) (xy -0.1524 -0.8001) (xy -0.16256 -0.76835) (xy -0.1651 -0.7366) (xy -0.1651 -0.11938)
						(xy -0.17272 -0.11176) (xy -0.19812 -0.0762) (xy -0.2032 -0.06604) (xy -0.20701 -0.05715) (xy -0.21209 -0.04699)
						(xy -0.2159 -0.03683) (xy -0.21844 -0.02667) (xy -0.22225 -0.01524) (xy -0.22352 -0.00508) (xy -0.22606 0.00508)
						(xy -0.22733 0.01651) (xy -0.22733 0.02667) (xy -0.2286 0.0381) (xy -0.22733 0.04953) (xy -0.22733 0.05969)
						(xy -0.22606 0.07112) (xy -0.22352 0.08128) (xy -0.22225 0.09144) (xy -0.21844 0.10287) (xy -0.2159 0.11303)
						(xy -0.21209 0.12319) (xy -0.20701 0.13335) (xy -0.2032 0.14224) (xy -0.19812 0.1524) (xy -0.17272 0.18796)
						(xy -0.1651 0.19558) (xy -0.1651 0.7366) (xy -0.16256 0.76835) (xy -0.1524 0.8001) (xy -0.13716 0.82804)
						(xy -0.11684 0.85344) (xy -0.09144 0.87376) (xy -0.0635 0.889) (xy -0.03175 0.89916) (xy 0 0.9017)
						(xy 0.03175 0.89916) (xy 0.0635 0.889) (xy 0.09144 0.87376) (xy 0.11684 0.85344) (xy 0.13716 0.82804)
						(xy 0.1524 0.8001) (xy 0.16256 0.76835) (xy 0.1651 0.7366) (xy 0.1651 0.19685) (xy 0.17272 0.18923)
						(xy 0.17907 0.18034) (xy 0.18669 0.17145) (xy 0.19177 0.16256) (xy 0.19812 0.15367) (xy 0.20828 0.13335)
						(xy 0.21971 0.10287) (xy 0.22225 0.09271) (xy 0.22479 0.08128) (xy 0.22606 0.07112) (xy 0.2286 0.05969)
						(xy 0.2286 0.01651) (xy 0.22606 0.00508) (xy 0.22479 -0.00508) (xy 0.22225 -0.01651) (xy 0.21971 -0.02667)
						(xy 0.20828 -0.05715) (xy 0.19812 -0.07747) (xy 0.19177 -0.08636) (xy 0.18669 -0.09525) (xy 0.17907 -0.10414)
						(xy 0.17272 -0.11303) (xy 0.1651 -0.12065) (xy 0.1651 -0.7366) (xy 0.16256 -0.76835) (xy 0.1524 -0.8001)
						(xy 0.13716 -0.82804) (xy 0.11684 -0.85344) (xy 0.09144 -0.87376) (xy 0.0635 -0.889) (xy 0.03175 -0.89916)
					)
					(width 0)
					(fill yes)
				)
			)
		)
		(pad "169" smd custom
			(at 21.150072 -4.100068 180)
			(size 0.1143 0.1143)
			(layers "B.Cu" "B.Mask" "B.Paste")
			(net "GND")
			(options
				(clearance outline)
				(anchor circle)
			)
			(primitives
				(gr_poly
					(pts
						(xy 0 -0.9017) (xy -0.03175 -0.89916) (xy -0.0635 -0.889) (xy -0.09144 -0.87376) (xy -0.11684 -0.85344)
						(xy -0.13716 -0.82804) (xy -0.1524 -0.8001) (xy -0.16256 -0.76835) (xy -0.1651 -0.7366) (xy -0.1651 -0.44958)
						(xy -0.17272 -0.44196) (xy -0.19812 -0.4064) (xy -0.2032 -0.39624) (xy -0.20701 -0.38735) (xy -0.21209 -0.37719)
						(xy -0.2159 -0.36703) (xy -0.21844 -0.35687) (xy -0.22225 -0.34544) (xy -0.22352 -0.33528) (xy -0.22606 -0.32512)
						(xy -0.22733 -0.31369) (xy -0.22733 -0.30353) (xy -0.2286 -0.2921) (xy -0.22733 -0.28067) (xy -0.22733 -0.27051)
						(xy -0.22606 -0.25908) (xy -0.22352 -0.24892) (xy -0.22225 -0.23876) (xy -0.21844 -0.22733) (xy -0.2159 -0.21717)
						(xy -0.21209 -0.20701) (xy -0.20701 -0.19685) (xy -0.2032 -0.18796) (xy -0.19812 -0.1778) (xy -0.17272 -0.14224)
						(xy -0.1651 -0.13462) (xy -0.1651 0.7366) (xy -0.16256 0.76835) (xy -0.1524 0.8001) (xy -0.13716 0.82804)
						(xy -0.11684 0.85344) (xy -0.09144 0.87376) (xy -0.0635 0.889) (xy -0.03175 0.89916) (xy 0 0.9017)
						(xy 0.03175 0.89916) (xy 0.0635 0.889) (xy 0.09144 0.87376) (xy 0.11684 0.85344) (xy 0.13716 0.82804)
						(xy 0.1524 0.8001) (xy 0.16256 0.76835) (xy 0.1651 0.7366) (xy 0.1651 -0.13462) (xy 0.17272 -0.14224)
						(xy 0.19812 -0.1778) (xy 0.2032 -0.18796) (xy 0.20701 -0.19685) (xy 0.21209 -0.20701) (xy 0.2159 -0.21717)
						(xy 0.21844 -0.22733) (xy 0.22225 -0.23876) (xy 0.22352 -0.24892) (xy 0.22606 -0.25908) (xy 0.22733 -0.27051)
						(xy 0.22733 -0.28067) (xy 0.2286 -0.2921) (xy 0.22733 -0.30353) (xy 0.22733 -0.31369) (xy 0.22606 -0.32512)
						(xy 0.22352 -0.33528) (xy 0.22225 -0.34544) (xy 0.21844 -0.35687) (xy 0.2159 -0.36703) (xy 0.21209 -0.37719)
						(xy 0.20701 -0.38735) (xy 0.2032 -0.39624) (xy 0.19812 -0.4064) (xy 0.17272 -0.44196) (xy 0.1651 -0.44958)
						(xy 0.1651 -0.7366) (xy 0.16256 -0.76835) (xy 0.1524 -0.8001) (xy 0.13716 -0.82804) (xy 0.11684 -0.85344)
						(xy 0.09144 -0.87376) (xy 0.0635 -0.889) (xy 0.03175 -0.89916)
					)
					(width 0)
					(fill yes)
				)
			)
		)
		(pad "170" smd custom
			(at 21.450046 4.100068 180)
			(size 0.1143 0.1143)
			(layers "B.Cu" "B.Mask" "B.Paste")
			(net "GND")
			(options
				(clearance outline)
				(anchor circle)
			)
			(primitives
				(gr_poly
					(pts
						(xy 0 -0.9017) (xy -0.03175 -0.89916) (xy -0.0635 -0.889) (xy -0.09144 -0.87376) (xy -0.11684 -0.85344)
						(xy -0.13716 -0.82804) (xy -0.1524 -0.8001) (xy -0.16256 -0.76835) (xy -0.1651 -0.7366) (xy -0.1651 0.13462)
						(xy -0.17272 0.14224) (xy -0.19812 0.1778) (xy -0.2032 0.18796) (xy -0.20701 0.19685) (xy -0.21209 0.20701)
						(xy -0.2159 0.21717) (xy -0.21844 0.22733) (xy -0.22225 0.23876) (xy -0.22352 0.24892) (xy -0.22606 0.25908)
						(xy -0.22733 0.27051) (xy -0.22733 0.28067) (xy -0.2286 0.2921) (xy -0.22733 0.30353) (xy -0.22733 0.31369)
						(xy -0.22606 0.32512) (xy -0.22352 0.33528) (xy -0.22225 0.34544) (xy -0.21844 0.35687) (xy -0.2159 0.36703)
						(xy -0.21209 0.37719) (xy -0.20701 0.38735) (xy -0.2032 0.39624) (xy -0.19812 0.4064) (xy -0.17272 0.44196)
						(xy -0.1651 0.44958) (xy -0.1651 0.7366) (xy -0.16256 0.76835) (xy -0.1524 0.8001) (xy -0.13716 0.82804)
						(xy -0.11684 0.85344) (xy -0.09144 0.87376) (xy -0.0635 0.889) (xy -0.03175 0.89916) (xy 0 0.9017)
						(xy 0.03175 0.89916) (xy 0.0635 0.889) (xy 0.09144 0.87376) (xy 0.11684 0.85344) (xy 0.13716 0.82804)
						(xy 0.1524 0.8001) (xy 0.16256 0.76835) (xy 0.1651 0.7366) (xy 0.1651 0.44958) (xy 0.17272 0.44196)
						(xy 0.19812 0.4064) (xy 0.2032 0.39624) (xy 0.20701 0.38735) (xy 0.21209 0.37719) (xy 0.2159 0.36703)
						(xy 0.21844 0.35687) (xy 0.22225 0.34544) (xy 0.22352 0.33528) (xy 0.22606 0.32512) (xy 0.22733 0.31369)
						(xy 0.22733 0.30353) (xy 0.2286 0.2921) (xy 0.22733 0.28067) (xy 0.22733 0.27051) (xy 0.22606 0.25908)
						(xy 0.22352 0.24892) (xy 0.22225 0.23876) (xy 0.21844 0.22733) (xy 0.2159 0.21717) (xy 0.21209 0.20701)
						(xy 0.20701 0.19685) (xy 0.2032 0.18796) (xy 0.19812 0.1778) (xy 0.17272 0.14224) (xy 0.1651 0.13462)
						(xy 0.1651 -0.7366) (xy 0.16256 -0.76835) (xy 0.1524 -0.8001) (xy 0.13716 -0.82804) (xy 0.11684 -0.85344)
						(xy 0.09144 -0.87376) (xy 0.0635 -0.889) (xy 0.03175 -0.89916)
					)
					(width 0)
					(fill yes)
				)
			)
		)
		(pad "171" smd custom
			(at 21.75002 -4.100068 180)
			(size 0.1143 0.1143)
			(layers "B.Cu" "B.Mask" "B.Paste")
			(net "M_B_DQS_DN6")
			(options
				(clearance outline)
				(anchor circle)
			)
			(primitives
				(gr_poly
					(pts
						(xy 0 -0.9017) (xy -0.03175 -0.89916) (xy -0.0635 -0.889) (xy -0.09144 -0.87376) (xy -0.11684 -0.85344)
						(xy -0.13716 -0.82804) (xy -0.1524 -0.8001) (xy -0.16256 -0.76835) (xy -0.1651 -0.7366) (xy -0.1651 -0.19685)
						(xy -0.17272 -0.18923) (xy -0.17907 -0.18034) (xy -0.18669 -0.17145) (xy -0.19177 -0.16256) (xy -0.19812 -0.15367)
						(xy -0.20828 -0.13335) (xy -0.21971 -0.10287) (xy -0.22225 -0.09271) (xy -0.22479 -0.08128) (xy -0.22606 -0.07112)
						(xy -0.2286 -0.05969) (xy -0.2286 -0.01651) (xy -0.22606 -0.00508) (xy -0.22479 0.00508) (xy -0.22225 0.01651)
						(xy -0.21971 0.02667) (xy -0.20828 0.05715) (xy -0.19812 0.07747) (xy -0.19177 0.08636) (xy -0.18669 0.09525)
						(xy -0.17907 0.10414) (xy -0.17272 0.11303) (xy -0.1651 0.12065) (xy -0.1651 0.7366) (xy -0.16256 0.76835)
						(xy -0.1524 0.8001) (xy -0.13716 0.82804) (xy -0.11684 0.85344) (xy -0.09144 0.87376) (xy -0.0635 0.889)
						(xy -0.03175 0.89916) (xy 0 0.9017) (xy 0.03175 0.89916) (xy 0.0635 0.889) (xy 0.09144 0.87376)
						(xy 0.11684 0.85344) (xy 0.13716 0.82804) (xy 0.1524 0.8001) (xy 0.16256 0.76835) (xy 0.1651 0.7366)
						(xy 0.1651 0.11938) (xy 0.17272 0.11176) (xy 0.19812 0.0762) (xy 0.2032 0.06604) (xy 0.20701 0.05715)
						(xy 0.21209 0.04699) (xy 0.2159 0.03683) (xy 0.21844 0.02667) (xy 0.22225 0.01524) (xy 0.22352 0.00508)
						(xy 0.22606 -0.00508) (xy 0.22733 -0.01651) (xy 0.22733 -0.02667) (xy 0.2286 -0.0381) (xy 0.22733 -0.04953)
						(xy 0.22733 -0.05969) (xy 0.22606 -0.07112) (xy 0.22352 -0.08128) (xy 0.22225 -0.09144) (xy 0.21844 -0.10287)
						(xy 0.2159 -0.11303) (xy 0.21209 -0.12319) (xy 0.20701 -0.13335) (xy 0.2032 -0.14224) (xy 0.19812 -0.1524)
						(xy 0.17272 -0.18796) (xy 0.1651 -0.19558) (xy 0.1651 -0.7366) (xy 0.16256 -0.76835) (xy 0.1524 -0.8001)
						(xy 0.13716 -0.82804) (xy 0.11684 -0.85344) (xy 0.09144 -0.87376) (xy 0.0635 -0.889) (xy 0.03175 -0.89916)
					)
					(width 0)
					(fill yes)
				)
			)
		)
		(pad "172" smd custom
			(at 22.049994 4.100068 180)
			(size 0.1143 0.1143)
			(layers "B.Cu" "B.Mask" "B.Paste")
			(net "GND")
			(options
				(clearance outline)
				(anchor circle)
			)
			(primitives
				(gr_poly
					(pts
						(xy 0 -0.9017) (xy -0.03175 -0.89916) (xy -0.0635 -0.889) (xy -0.09144 -0.87376) (xy -0.11684 -0.85344)
						(xy -0.13716 -0.82804) (xy -0.1524 -0.8001) (xy -0.16256 -0.76835) (xy -0.1651 -0.7366) (xy -0.1651 -0.11938)
						(xy -0.17272 -0.11176) (xy -0.19812 -0.0762) (xy -0.2032 -0.06604) (xy -0.20701 -0.05715) (xy -0.21209 -0.04699)
						(xy -0.2159 -0.03683) (xy -0.21844 -0.02667) (xy -0.22225 -0.01524) (xy -0.22352 -0.00508) (xy -0.22606 0.00508)
						(xy -0.22733 0.01651) (xy -0.22733 0.02667) (xy -0.2286 0.0381) (xy -0.22733 0.04953) (xy -0.22733 0.05969)
						(xy -0.22606 0.07112) (xy -0.22352 0.08128) (xy -0.22225 0.09144) (xy -0.21844 0.10287) (xy -0.2159 0.11303)
						(xy -0.21209 0.12319) (xy -0.20701 0.13335) (xy -0.2032 0.14224) (xy -0.19812 0.1524) (xy -0.17272 0.18796)
						(xy -0.1651 0.19558) (xy -0.1651 0.7366) (xy -0.16256 0.76835) (xy -0.1524 0.8001) (xy -0.13716 0.82804)
						(xy -0.11684 0.85344) (xy -0.09144 0.87376) (xy -0.0635 0.889) (xy -0.03175 0.89916) (xy 0 0.9017)
						(xy 0.03175 0.89916) (xy 0.0635 0.889) (xy 0.09144 0.87376) (xy 0.11684 0.85344) (xy 0.13716 0.82804)
						(xy 0.1524 0.8001) (xy 0.16256 0.76835) (xy 0.1651 0.7366) (xy 0.1651 0.19685) (xy 0.17272 0.18923)
						(xy 0.17907 0.18034) (xy 0.18669 0.17145) (xy 0.19177 0.16256) (xy 0.19812 0.15367) (xy 0.20828 0.13335)
						(xy 0.21971 0.10287) (xy 0.22225 0.09271) (xy 0.22479 0.08128) (xy 0.22606 0.07112) (xy 0.2286 0.05969)
						(xy 0.2286 0.01651) (xy 0.22606 0.00508) (xy 0.22479 -0.00508) (xy 0.22225 -0.01651) (xy 0.21971 -0.02667)
						(xy 0.20828 -0.05715) (xy 0.19812 -0.07747) (xy 0.19177 -0.08636) (xy 0.18669 -0.09525) (xy 0.17907 -0.10414)
						(xy 0.17272 -0.11303) (xy 0.1651 -0.12065) (xy 0.1651 -0.7366) (xy 0.16256 -0.76835) (xy 0.1524 -0.8001)
						(xy 0.13716 -0.82804) (xy 0.11684 -0.85344) (xy 0.09144 -0.87376) (xy 0.0635 -0.889) (xy 0.03175 -0.89916)
					)
					(width 0)
					(fill yes)
				)
			)
		)
		(pad "173" smd custom
			(at 22.349968 -4.100068 180)
			(size 0.1143 0.1143)
			(layers "B.Cu" "B.Mask" "B.Paste")
			(net "M_B_DQS_DP6")
			(options
				(clearance outline)
				(anchor circle)
			)
			(primitives
				(gr_poly
					(pts
						(xy 0 -0.9017) (xy -0.03175 -0.89916) (xy -0.0635 -0.889) (xy -0.09144 -0.87376) (xy -0.11684 -0.85344)
						(xy -0.13716 -0.82804) (xy -0.1524 -0.8001) (xy -0.16256 -0.76835) (xy -0.1651 -0.7366) (xy -0.1651 -0.44958)
						(xy -0.17272 -0.44196) (xy -0.19812 -0.4064) (xy -0.2032 -0.39624) (xy -0.20701 -0.38735) (xy -0.21209 -0.37719)
						(xy -0.2159 -0.36703) (xy -0.21844 -0.35687) (xy -0.22225 -0.34544) (xy -0.22352 -0.33528) (xy -0.22606 -0.32512)
						(xy -0.22733 -0.31369) (xy -0.22733 -0.30353) (xy -0.2286 -0.2921) (xy -0.22733 -0.28067) (xy -0.22733 -0.27051)
						(xy -0.22606 -0.25908) (xy -0.22352 -0.24892) (xy -0.22225 -0.23876) (xy -0.21844 -0.22733) (xy -0.2159 -0.21717)
						(xy -0.21209 -0.20701) (xy -0.20701 -0.19685) (xy -0.2032 -0.18796) (xy -0.19812 -0.1778) (xy -0.17272 -0.14224)
						(xy -0.1651 -0.13462) (xy -0.1651 0.7366) (xy -0.16256 0.76835) (xy -0.1524 0.8001) (xy -0.13716 0.82804)
						(xy -0.11684 0.85344) (xy -0.09144 0.87376) (xy -0.0635 0.889) (xy -0.03175 0.89916) (xy 0 0.9017)
						(xy 0.03175 0.89916) (xy 0.0635 0.889) (xy 0.09144 0.87376) (xy 0.11684 0.85344) (xy 0.13716 0.82804)
						(xy 0.1524 0.8001) (xy 0.16256 0.76835) (xy 0.1651 0.7366) (xy 0.1651 -0.13462) (xy 0.17272 -0.14224)
						(xy 0.19812 -0.1778) (xy 0.2032 -0.18796) (xy 0.20701 -0.19685) (xy 0.21209 -0.20701) (xy 0.2159 -0.21717)
						(xy 0.21844 -0.22733) (xy 0.22225 -0.23876) (xy 0.22352 -0.24892) (xy 0.22606 -0.25908) (xy 0.22733 -0.27051)
						(xy 0.22733 -0.28067) (xy 0.2286 -0.2921) (xy 0.22733 -0.30353) (xy 0.22733 -0.31369) (xy 0.22606 -0.32512)
						(xy 0.22352 -0.33528) (xy 0.22225 -0.34544) (xy 0.21844 -0.35687) (xy 0.2159 -0.36703) (xy 0.21209 -0.37719)
						(xy 0.20701 -0.38735) (xy 0.2032 -0.39624) (xy 0.19812 -0.4064) (xy 0.17272 -0.44196) (xy 0.1651 -0.44958)
						(xy 0.1651 -0.7366) (xy 0.16256 -0.76835) (xy 0.1524 -0.8001) (xy 0.13716 -0.82804) (xy 0.11684 -0.85344)
						(xy 0.09144 -0.87376) (xy 0.0635 -0.889) (xy 0.03175 -0.89916)
					)
					(width 0)
					(fill yes)
				)
			)
		)
		(pad "174" smd custom
			(at 22.649942 4.100068 180)
			(size 0.1143 0.1143)
			(layers "B.Cu" "B.Mask" "B.Paste")
			(net "M_B_DQ54")
			(options
				(clearance outline)
				(anchor circle)
			)
			(primitives
				(gr_poly
					(pts
						(xy 0 -0.9017) (xy -0.03175 -0.89916) (xy -0.0635 -0.889) (xy -0.09144 -0.87376) (xy -0.11684 -0.85344)
						(xy -0.13716 -0.82804) (xy -0.1524 -0.8001) (xy -0.16256 -0.76835) (xy -0.1651 -0.7366) (xy -0.1651 0.13462)
						(xy -0.17272 0.14224) (xy -0.19812 0.1778) (xy -0.2032 0.18796) (xy -0.20701 0.19685) (xy -0.21209 0.20701)
						(xy -0.2159 0.21717) (xy -0.21844 0.22733) (xy -0.22225 0.23876) (xy -0.22352 0.24892) (xy -0.22606 0.25908)
						(xy -0.22733 0.27051) (xy -0.22733 0.28067) (xy -0.2286 0.2921) (xy -0.22733 0.30353) (xy -0.22733 0.31369)
						(xy -0.22606 0.32512) (xy -0.22352 0.33528) (xy -0.22225 0.34544) (xy -0.21844 0.35687) (xy -0.2159 0.36703)
						(xy -0.21209 0.37719) (xy -0.20701 0.38735) (xy -0.2032 0.39624) (xy -0.19812 0.4064) (xy -0.17272 0.44196)
						(xy -0.1651 0.44958) (xy -0.1651 0.7366) (xy -0.16256 0.76835) (xy -0.1524 0.8001) (xy -0.13716 0.82804)
						(xy -0.11684 0.85344) (xy -0.09144 0.87376) (xy -0.0635 0.889) (xy -0.03175 0.89916) (xy 0 0.9017)
						(xy 0.03175 0.89916) (xy 0.0635 0.889) (xy 0.09144 0.87376) (xy 0.11684 0.85344) (xy 0.13716 0.82804)
						(xy 0.1524 0.8001) (xy 0.16256 0.76835) (xy 0.1651 0.7366) (xy 0.1651 0.44958) (xy 0.17272 0.44196)
						(xy 0.19812 0.4064) (xy 0.2032 0.39624) (xy 0.20701 0.38735) (xy 0.21209 0.37719) (xy 0.2159 0.36703)
						(xy 0.21844 0.35687) (xy 0.22225 0.34544) (xy 0.22352 0.33528) (xy 0.22606 0.32512) (xy 0.22733 0.31369)
						(xy 0.22733 0.30353) (xy 0.2286 0.2921) (xy 0.22733 0.28067) (xy 0.22733 0.27051) (xy 0.22606 0.25908)
						(xy 0.22352 0.24892) (xy 0.22225 0.23876) (xy 0.21844 0.22733) (xy 0.2159 0.21717) (xy 0.21209 0.20701)
						(xy 0.20701 0.19685) (xy 0.2032 0.18796) (xy 0.19812 0.1778) (xy 0.17272 0.14224) (xy 0.1651 0.13462)
						(xy 0.1651 -0.7366) (xy 0.16256 -0.76835) (xy 0.1524 -0.8001) (xy 0.13716 -0.82804) (xy 0.11684 -0.85344)
						(xy 0.09144 -0.87376) (xy 0.0635 -0.889) (xy 0.03175 -0.89916)
					)
					(width 0)
					(fill yes)
				)
			)
		)
	)
)
